(kicad_pcb
	(version 20260206)
	(generator "pcbnew")
	(generator_version "10.0")
	(general
		(thickness 1.6)
		(legacy_teardrops no)
	)
	(paper "A4")
	(title_block
		(title "01162023_DA0F0TEBIF0_F0T_Expander_BD_F_brd_V02_OCP.brd")
		(comment 1 "Grand Teton / footprints 8680-8686 of 9728")
	)
	(layers
		(0 "F.Cu" signal "TOP")
		(4 "In1.Cu" signal "GND")
		(6 "In2.Cu" signal "VCC")
		(8 "In3.Cu" signal "VCC1")
		(10 "In4.Cu" signal "GND1")
		(12 "In5.Cu" signal "IN1")
		(14 "In6.Cu" signal "GND2")
		(16 "In7.Cu" signal "IN2")
		(18 "In8.Cu" signal "GND3")
		(20 "In9.Cu" signal "IN3")
		(22 "In10.Cu" signal "GND4")
		(24 "In11.Cu" signal "IN4")
		(26 "In12.Cu" signal "GND5")
		(28 "In13.Cu" signal "IN5")
		(30 "In14.Cu" signal "GND6")
		(32 "In15.Cu" signal "IN6")
		(34 "In16.Cu" signal "GND7")
		(2 "B.Cu" signal "BOTTOM")
		(9 "F.Adhes" user "F.Adhesive")
		(11 "B.Adhes" user "B.Adhesive")
		(13 "F.Paste" user "Package Geometry/Pastemask Top")
		(15 "B.Paste" user "Package Geometry/Pastemask Bottom")
		(5 "F.SilkS" user "Ref Des/Silkscreen Top")
		(7 "B.SilkS" user "Ref Des/Silkscreen Bottom")
		(1 "F.Mask" user "Board Geometry/Soldermask Top")
		(3 "B.Mask" user "Board Geometry/Soldermask Bottom")
		(17 "Dwgs.User" user "User.Drawings")
		(19 "Cmts.User" user "User.Comments")
		(21 "Eco1.User" user "User.Eco1")
		(23 "Eco2.User" user "User.Eco2")
		(25 "Edge.Cuts" user "Board Geometry/Outline")
		(27 "Margin" user)
		(31 "F.CrtYd" user "Package Geometry/Place Bound Top")
		(29 "B.CrtYd" user "Package Geometry/Place Bound Bottom")
		(35 "F.Fab" user "Ref Des/Assembly Top")
		(33 "B.Fab" user "Ref Des/Assembly Bottom")
	)
	(footprint ""
		(layer "B.Cu")
		(at 281.065986 -138.421618 180)
		(property "Reference" "R207"
			(at 0 0 0)
			(layer "B.SilkS")
			(hide yes)
			(effects
				(font
					(size 1.27 1.27)
				)
				(justify mirror)
			)
		)
		(property "Value" ""
			(at 0 0 0)
			(layer "B.Fab")
			(effects
				(font
					(size 1.27 1.27)
				)
				(justify mirror)
			)
		)
		(duplicate_pad_numbers_are_jumpers no)
		(fp_line
			(start 0.7874 0.4064)
			(end 0.7874 -0.4064)
			(stroke
				(width 0.1524)
				(type default)
			)
			(layer "B.SilkS")
		)
		(fp_line
			(start 0.7874 -0.4064)
			(end -0.7874 -0.4064)
			(stroke
				(width 0.1524)
				(type default)
			)
			(layer "B.SilkS")
		)
		(fp_line
			(start -0.7874 0.4064)
			(end 0.7874 0.4064)
			(stroke
				(width 0.1524)
				(type default)
			)
			(layer "B.SilkS")
		)
		(fp_line
			(start -0.7874 -0.4064)
			(end -0.7874 0.4064)
			(stroke
				(width 0.1524)
				(type default)
			)
			(layer "B.SilkS")
		)
		(fp_line
			(start 0.67945 0.3048)
			(end 0.67945 -0.305054)
			(stroke
				(width 0.1)
				(type default)
			)
			(layer "B.Fab")
		)
		(fp_line
			(start 0.67945 -0.305054)
			(end 0.12065 -0.305054)
			(stroke
				(width 0.1)
				(type default)
			)
			(layer "B.Fab")
		)
		(fp_line
			(start 0.12065 0.3048)
			(end 0.67945 0.3048)
			(stroke
				(width 0.1)
				(type default)
			)
			(layer "B.Fab")
		)
		(fp_line
			(start 0.12065 0.2794)
			(end 0.12065 0.3048)
			(stroke
				(width 0.1)
				(type default)
			)
			(layer "B.Fab")
		)
		(fp_line
			(start 0.12065 -0.2794)
			(end -0.12065 -0.2794)
			(stroke
				(width 0.1)
				(type default)
			)
			(layer "B.Fab")
		)
		(fp_line
			(start 0.12065 -0.305054)
			(end 0.12065 -0.2794)
			(stroke
				(width 0.1)
				(type default)
			)
			(layer "B.Fab")
		)
		(fp_line
			(start -0.120396 0.3048)
			(end -0.120396 0.2794)
			(stroke
				(width 0.1)
				(type default)
			)
			(layer "B.Fab")
		)
		(fp_line
			(start -0.120396 0.2794)
			(end 0.12065 0.2794)
			(stroke
				(width 0.1)
				(type default)
			)
			(layer "B.Fab")
		)
		(fp_line
			(start -0.12065 -0.2794)
			(end -0.12065 -0.3048)
			(stroke
				(width 0.1)
				(type default)
			)
			(layer "B.Fab")
		)
		(fp_line
			(start -0.12065 -0.3048)
			(end -0.67945 -0.3048)
			(stroke
				(width 0.1)
				(type default)
			)
			(layer "B.Fab")
		)
		(fp_line
			(start -0.67945 0.3048)
			(end -0.120396 0.3048)
			(stroke
				(width 0.1)
				(type default)
			)
			(layer "B.Fab")
		)
		(fp_line
			(start -0.67945 -0.3048)
			(end -0.67945 0.3048)
			(stroke
				(width 0.1)
				(type default)
			)
			(layer "B.Fab")
		)
		(pad "1" smd circle
			(at 0.40005 0)
			(size 0 0)
			(layers "B.Cu" "B.Mask" "B.Paste")
			(net "NIC4_AUX_PWR_EN_R")
		)
		(pad "2" smd circle
			(at -0.40005 0)
			(size 0 0)
			(layers "B.Cu" "B.Mask" "B.Paste")
			(net "NIC4_AUX_PWR_EN")
		)
	)
	(footprint ""
		(layer "B.Cu")
		(at 269.099792 -364.979204 -90)
		(property "Reference" "PC6001"
			(at 0 0 90)
			(layer "B.SilkS")
			(hide yes)
			(effects
				(font
					(size 1.27 1.27)
				)
				(justify mirror)
			)
		)
		(property "Value" ""
			(at 0 0 90)
			(layer "B.Fab")
			(effects
				(font
					(size 1.27 1.27)
				)
				(justify mirror)
			)
		)
		(duplicate_pad_numbers_are_jumpers no)
		(fp_line
			(start -0.7874 0.4064)
			(end 0.7874 0.4064)
			(stroke
				(width 0.1524)
				(type default)
			)
			(layer "B.SilkS")
		)
		(fp_line
			(start 0.7874 0.4064)
			(end 0.7874 -0.4064)
			(stroke
				(width 0.1524)
				(type default)
			)
			(layer "B.SilkS")
		)
		(fp_line
			(start -0.7874 -0.4064)
			(end -0.7874 0.4064)
			(stroke
				(width 0.1524)
				(type default)
			)
			(layer "B.SilkS")
		)
		(fp_line
			(start 0.7874 -0.4064)
			(end -0.7874 -0.4064)
			(stroke
				(width 0.1524)
				(type default)
			)
			(layer "B.SilkS")
		)
		(fp_line
			(start -0.67945 0.3048)
			(end -0.120396 0.3048)
			(stroke
				(width 0.1)
				(type default)
			)
			(layer "B.Fab")
		)
		(fp_line
			(start -0.120396 0.3048)
			(end -0.120396 0.2794)
			(stroke
				(width 0.1)
				(type default)
			)
			(layer "B.Fab")
		)
		(fp_line
			(start 0.12065 0.3048)
			(end 0.67945 0.3048)
			(stroke
				(width 0.1)
				(type default)
			)
			(layer "B.Fab")
		)
		(fp_line
			(start 0.67945 0.3048)
			(end 0.67945 -0.305054)
			(stroke
				(width 0.1)
				(type default)
			)
			(layer "B.Fab")
		)
		(fp_line
			(start -0.120396 0.2794)
			(end 0.12065 0.2794)
			(stroke
				(width 0.1)
				(type default)
			)
			(layer "B.Fab")
		)
		(fp_line
			(start 0.12065 0.2794)
			(end 0.12065 0.3048)
			(stroke
				(width 0.1)
				(type default)
			)
			(layer "B.Fab")
		)
		(fp_line
			(start -0.12065 -0.2794)
			(end -0.12065 -0.3048)
			(stroke
				(width 0.1)
				(type default)
			)
			(layer "B.Fab")
		)
		(fp_line
			(start 0.12065 -0.2794)
			(end -0.12065 -0.2794)
			(stroke
				(width 0.1)
				(type default)
			)
			(layer "B.Fab")
		)
		(fp_line
			(start -0.67945 -0.3048)
			(end -0.67945 0.3048)
			(stroke
				(width 0.1)
				(type default)
			)
			(layer "B.Fab")
		)
		(fp_line
			(start -0.12065 -0.3048)
			(end -0.67945 -0.3048)
			(stroke
				(width 0.1)
				(type default)
			)
			(layer "B.Fab")
		)
		(fp_line
			(start 0.12065 -0.305054)
			(end 0.12065 -0.2794)
			(stroke
				(width 0.1)
				(type default)
			)
			(layer "B.Fab")
		)
		(fp_line
			(start 0.67945 -0.305054)
			(end 0.12065 -0.305054)
			(stroke
				(width 0.1)
				(type default)
			)
			(layer "B.Fab")
		)
		(pad "1" smd circle
			(at 0.40005 0 90)
			(size 0 0)
			(layers "B.Cu" "B.Mask" "B.Paste")
			(net "P12V_AUX")
		)
		(pad "2" smd circle
			(at -0.40005 0 90)
			(size 0 0)
			(layers "B.Cu" "B.Mask" "B.Paste")
			(net "P12V_HSC_GATE2")
		)
	)
	(footprint ""
		(layer "B.Cu")
		(at 46.34992 -290.674806)
		(property "Reference" "C3006"
			(at 0 0 0)
			(layer "B.SilkS")
			(hide yes)
			(effects
				(font
					(size 1.27 1.27)
				)
				(justify mirror)
			)
		)
		(property "Value" ""
			(at 0 0 0)
			(layer "B.Fab")
			(effects
				(font
					(size 1.27 1.27)
				)
				(justify mirror)
			)
		)
		(duplicate_pad_numbers_are_jumpers no)
		(fp_line
			(start -0.299974 -0.150114)
			(end -0.299974 0.150114)
			(stroke
				(width 0.1)
				(type default)
			)
			(layer "B.Fab")
		)
		(fp_line
			(start -0.299974 0.150114)
			(end 0.299974 0.150114)
			(stroke
				(width 0.1)
				(type default)
			)
			(layer "B.Fab")
		)
		(fp_line
			(start 0.299974 -0.150114)
			(end -0.299974 -0.150114)
			(stroke
				(width 0.1)
				(type default)
			)
			(layer "B.Fab")
		)
		(fp_line
			(start 0.299974 0.150114)
			(end 0.299974 -0.150114)
			(stroke
				(width 0.1)
				(type default)
			)
			(layer "B.Fab")
		)
		(pad "1" smd rect
			(at 0.2667 0 180)
			(size 0.3048 0.381)
			(layers "B.Cu" "B.Mask" "B.Paste")
			(net "P1V8_PEX")
		)
		(pad "2" smd rect
			(at -0.2667 0 180)
			(size 0.3048 0.381)
			(layers "B.Cu" "B.Mask" "B.Paste")
			(net "GND")
		)
	)
	(footprint ""
		(layer "B.Cu")
		(at 361.912408 -324.163944 -90)
		(property "Reference" "C4385"
			(at 0 0 90)
			(layer "B.SilkS")
			(hide yes)
			(effects
				(font
					(size 1.27 1.27)
				)
				(justify mirror)
			)
		)
		(property "Value" ""
			(at 0 0 90)
			(layer "B.Fab")
			(effects
				(font
					(size 1.27 1.27)
				)
				(justify mirror)
			)
		)
		(duplicate_pad_numbers_are_jumpers no)
		(fp_line
			(start -1.2954 0.5842)
			(end 1.2954 0.5842)
			(stroke
				(width 0.1524)
				(type default)
			)
			(layer "B.SilkS")
		)
		(fp_line
			(start 1.2954 0.5842)
			(end 1.2954 -0.5842)
			(stroke
				(width 0.1524)
				(type default)
			)
			(layer "B.SilkS")
		)
		(fp_line
			(start -1.2954 -0.5842)
			(end -1.2954 0.5842)
			(stroke
				(width 0.1524)
				(type default)
			)
			(layer "B.SilkS")
		)
		(fp_line
			(start 1.2954 -0.5842)
			(end -1.2954 -0.5842)
			(stroke
				(width 0.1524)
				(type default)
			)
			(layer "B.SilkS")
		)
		(fp_line
			(start -0.8636 0.4572)
			(end 0.8636 0.4572)
			(stroke
				(width 0.1)
				(type default)
			)
			(layer "B.Fab")
		)
		(fp_line
			(start 0.8636 0.4572)
			(end 0.8636 0.4064)
			(stroke
				(width 0.1)
				(type default)
			)
			(layer "B.Fab")
		)
		(fp_line
			(start -1.1938 0.4064)
			(end -0.8636 0.4064)
			(stroke
				(width 0.1)
				(type default)
			)
			(layer "B.Fab")
		)
		(fp_line
			(start -0.8636 0.4064)
			(end -0.8636 0.4572)
			(stroke
				(width 0.1)
				(type default)
			)
			(layer "B.Fab")
		)
		(fp_line
			(start 0.8636 0.4064)
			(end 1.1938 0.4064)
			(stroke
				(width 0.1)
				(type default)
			)
			(layer "B.Fab")
		)
		(fp_line
			(start 1.1938 0.4064)
			(end 1.1938 -0.4064)
			(stroke
				(width 0.1)
				(type default)
			)
			(layer "B.Fab")
		)
		(fp_line
			(start -1.1938 -0.4064)
			(end -1.1938 0.4064)
			(stroke
				(width 0.1)
				(type default)
			)
			(layer "B.Fab")
		)
		(fp_line
			(start -0.8636 -0.4064)
			(end -1.1938 -0.4064)
			(stroke
				(width 0.1)
				(type default)
			)
			(layer "B.Fab")
		)
		(fp_line
			(start 0.8636 -0.4064)
			(end 0.8636 -0.4572)
			(stroke
				(width 0.1)
				(type default)
			)
			(layer "B.Fab")
		)
		(fp_line
			(start 1.1938 -0.4064)
			(end 0.8636 -0.4064)
			(stroke
				(width 0.1)
				(type default)
			)
			(layer "B.Fab")
		)
		(fp_line
			(start -0.8636 -0.4572)
			(end -0.8636 -0.4064)
			(stroke
				(width 0.1)
				(type default)
			)
			(layer "B.Fab")
		)
		(fp_line
			(start 0.8636 -0.4572)
			(end -0.8636 -0.4572)
			(stroke
				(width 0.1)
				(type default)
			)
			(layer "B.Fab")
		)
		(pad "1" smd rect
			(at 0.7366 0 180)
			(size 0.7112 0.8128)
			(layers "B.Cu" "B.Mask" "B.Paste")
			(net "P0V8_SERDES_VDDA_PEX3_C11")
		)
		(pad "2" smd rect
			(at -0.7366 0 180)
			(size 0.7112 0.8128)
			(layers "B.Cu" "B.Mask" "B.Paste")
			(net "GND")
		)
	)
	(footprint ""
		(layer "B.Cu")
		(at 399.400014 -299.699934 -90)
		(property "Reference" "C1944"
			(at 0 0 90)
			(layer "B.SilkS")
			(hide yes)
			(effects
				(font
					(size 1.27 1.27)
				)
				(justify mirror)
			)
		)
		(property "Value" ""
			(at 0 0 90)
			(layer "B.Fab")
			(effects
				(font
					(size 1.27 1.27)
				)
				(justify mirror)
			)
		)
		(duplicate_pad_numbers_are_jumpers no)
		(fp_line
			(start -0.299974 0.150114)
			(end 0.299974 0.150114)
			(stroke
				(width 0.1)
				(type default)
			)
			(layer "B.Fab")
		)
		(fp_line
			(start 0.299974 0.150114)
			(end 0.299974 -0.150114)
			(stroke
				(width 0.1)
				(type default)
			)
			(layer "B.Fab")
		)
		(fp_line
			(start -0.299974 -0.150114)
			(end -0.299974 0.150114)
			(stroke
				(width 0.1)
				(type default)
			)
			(layer "B.Fab")
		)
		(fp_line
			(start 0.299974 -0.150114)
			(end -0.299974 -0.150114)
			(stroke
				(width 0.1)
				(type default)
			)
			(layer "B.Fab")
		)
		(pad "1" smd rect
			(at 0.2667 0 90)
			(size 0.3048 0.381)
			(layers "B.Cu" "B.Mask" "B.Paste")
			(net "P0V8_SERDES_VDDA_PEX3")
		)
		(pad "2" smd rect
			(at -0.2667 0 90)
			(size 0.3048 0.381)
			(layers "B.Cu" "B.Mask" "B.Paste")
			(net "GND")
		)
	)
	(footprint ""
		(layer "B.Cu")
		(at 281.874722 -297.79976 90)
		(property "Reference" "C1642"
			(at 0 0 90)
			(layer "B.SilkS")
			(hide yes)
			(effects
				(font
					(size 1.27 1.27)
				)
				(justify mirror)
			)
		)
		(property "Value" ""
			(at 0 0 90)
			(layer "B.Fab")
			(effects
				(font
					(size 1.27 1.27)
				)
				(justify mirror)
			)
		)
		(duplicate_pad_numbers_are_jumpers no)
		(fp_line
			(start 0.299974 -0.150114)
			(end -0.299974 -0.150114)
			(stroke
				(width 0.1)
				(type default)
			)
			(layer "B.Fab")
		)
		(fp_line
			(start -0.299974 -0.150114)
			(end -0.299974 0.150114)
			(stroke
				(width 0.1)
				(type default)
			)
			(layer "B.Fab")
		)
		(fp_line
			(start 0.299974 0.150114)
			(end 0.299974 -0.150114)
			(stroke
				(width 0.1)
				(type default)
			)
			(layer "B.Fab")
		)
		(fp_line
			(start -0.299974 0.150114)
			(end 0.299974 0.150114)
			(stroke
				(width 0.1)
				(type default)
			)
			(layer "B.Fab")
		)
		(pad "1" smd rect
			(at 0.2667 0 270)
			(size 0.3048 0.381)
			(layers "B.Cu" "B.Mask" "B.Paste")
			(net "P0V8_PEX2")
		)
		(pad "2" smd rect
			(at -0.2667 0 270)
			(size 0.3048 0.381)
			(layers "B.Cu" "B.Mask" "B.Paste")
			(net "GND")
		)
	)
	(footprint ""
		(layer "B.Cu")
		(at 116.788184 -317.6778 180)
		(property "Reference" "C4208"
			(at 0 0 0)
			(layer "B.SilkS")
			(hide yes)
			(effects
				(font
					(size 1.27 1.27)
				)
				(justify mirror)
			)
		)
		(property "Value" ""
			(at 0 0 0)
			(layer "B.Fab")
			(effects
				(font
					(size 1.27 1.27)
				)
				(justify mirror)
			)
		)
		(duplicate_pad_numbers_are_jumpers no)
		(fp_line
			(start 0.299974 0.150114)
			(end 0.299974 -0.150114)
			(stroke
				(width 0.1)
				(type default)
			)
			(layer "B.Fab")
		)
		(fp_line
			(start 0.299974 -0.150114)
			(end -0.299974 -0.150114)
			(stroke
				(width 0.1)
				(type default)
			)
			(layer "B.Fab")
		)
		(fp_line
			(start -0.299974 0.150114)
			(end 0.299974 0.150114)
			(stroke
				(width 0.1)
				(type default)
			)
			(layer "B.Fab")
		)
		(fp_line
			(start -0.299974 -0.150114)
			(end -0.299974 0.150114)
			(stroke
				(width 0.1)
				(type default)
			)
			(layer "B.Fab")
		)
		(pad "1" smd rect
			(at 0.2667 0)
			(size 0.3048 0.381)
			(layers "B.Cu" "B.Mask" "B.Paste")
			(net "P0V8_SERDES_VDDA_PEX0")
		)
		(pad "2" smd rect
			(at -0.2667 0)
			(size 0.3048 0.381)
			(layers "B.Cu" "B.Mask" "B.Paste")
			(net "GND")
		)
	)
)
